# S9S_MB_2U (Grand Teton) — schematic netlist excerpt (pin names and nets, part order shuffled) for the footprints in the layout excerpt that follows; sources: Cadence DE-HDL packaged netlist, KiCad conversion of 03242023_DA0F0TMBIJ0_F0T_Motherboard_J_brd_V01_OCP.brd

PC2162  Q_CAP  100PF 50V 5% EMPTY  pkg 0402  page 157 : A = P3V3_OCP_GATE_1 ; B = GND
R2411  Q_RES  33.2 1% CHIP  pkg 0402LF  page 194 : A = SMB_M2_P0_1V8AUX_SCL_R ; B = SMB_M2_P0_1V8AUX_SCL

(kicad_pcb
	(version 20260206)
	(generator "pcbnew")
	(generator_version "10.0")
	(general
		(thickness 1.6)
		(legacy_teardrops no)
	)
	(paper "A4")
	(title_block
		(title "03242023_DA0F0TMBIJ0_F0T_Motherboard_J_brd_V01_OCP.brd")
		(comment 1 "Grand Teton / footprints 2702-2703 of 6105")
	)
	(layers
		(0 "F.Cu" signal "TOP")
		(4 "In1.Cu" signal "GND")
		(6 "In2.Cu" signal "IN1")
		(8 "In3.Cu" signal "GND1")
		(10 "In4.Cu" signal "IN2")
		(12 "In5.Cu" signal "GND2")
		(14 "In6.Cu" signal "IN3")
		(16 "In7.Cu" signal "GND3")
		(18 "In8.Cu" signal "VCC")
		(20 "In9.Cu" signal "VCC1")
		(22 "In10.Cu" signal "GND4")
		(24 "In11.Cu" signal "IN4")
		(26 "In12.Cu" signal "GND5")
		(28 "In13.Cu" signal "IN5")
		(30 "In14.Cu" signal "GND6")
		(32 "In15.Cu" signal "IN6")
		(34 "In16.Cu" signal "GND7")
		(2 "B.Cu" signal "BOTTOM")
		(9 "F.Adhes" user "F.Adhesive")
		(11 "B.Adhes" user "B.Adhesive")
		(13 "F.Paste" user "Package Geometry/Pastemask Top")
		(15 "B.Paste" user "Package Geometry/Pastemask Bottom")
		(5 "F.SilkS" user "Ref Des/Silkscreen Top")
		(7 "B.SilkS" user "Ref Des/Silkscreen Bottom")
		(1 "F.Mask" user "Board Geometry/Soldermask Top")
		(3 "B.Mask" user "Board Geometry/Soldermask Bottom")
		(17 "Dwgs.User" user "User.Drawings")
		(19 "Cmts.User" user "User.Comments")
		(21 "Eco1.User" user "User.Eco1")
		(23 "Eco2.User" user "User.Eco2")
		(25 "Edge.Cuts" user "Board Geometry/Outline")
		(27 "Margin" user)
		(31 "F.CrtYd" user "Package Geometry/Place Bound Top")
		(29 "B.CrtYd" user "Package Geometry/Place Bound Bottom")
		(35 "F.Fab" user "Ref Des/Assembly Top")
		(33 "B.Fab" user "Ref Des/Assembly Bottom")
	)
	(footprint ""
		(layer "F.Cu")
		(at 145.34388 -57.241948 180)
		(property "Reference" "R2411"
			(at 0 0 180)
			(layer "F.SilkS")
			(hide yes)
			(effects
				(font
					(size 1.27 1.27)
				)
			)
		)
		(property "Value" ""
			(at 0 0 180)
			(layer "F.Fab")
			(effects
				(font
					(size 1.27 1.27)
				)
			)
		)
		(duplicate_pad_numbers_are_jumpers no)
		(fp_line
			(start 0.7874 0.4064)
			(end -0.7874 0.4064)
			(stroke
				(width 0.1524)
				(type default)
			)
			(layer "F.SilkS")
		)
		(fp_line
			(start 0.7874 -0.4064)
			(end 0.7874 0.4064)
			(stroke
				(width 0.1524)
				(type default)
			)
			(layer "F.SilkS")
		)
		(fp_line
			(start -0.7874 0.4064)
			(end -0.7874 -0.4064)
			(stroke
				(width 0.1524)
				(type default)
			)
			(layer "F.SilkS")
		)
		(fp_line
			(start -0.7874 -0.4064)
			(end 0.7874 -0.4064)
			(stroke
				(width 0.1524)
				(type default)
			)
			(layer "F.SilkS")
		)
		(fp_line
			(start 0.67945 0.3048)
			(end 0.120396 0.3048)
			(stroke
				(width 0.1)
				(type default)
			)
			(layer "F.Fab")
		)
		(fp_line
			(start 0.67945 -0.3048)
			(end 0.67945 0.3048)
			(stroke
				(width 0.1)
				(type default)
			)
			(layer "F.Fab")
		)
		(fp_line
			(start 0.12065 -0.2794)
			(end 0.12065 -0.3048)
			(stroke
				(width 0.1)
				(type default)
			)
			(layer "F.Fab")
		)
		(fp_line
			(start 0.12065 -0.3048)
			(end 0.67945 -0.3048)
			(stroke
				(width 0.1)
				(type default)
			)
			(layer "F.Fab")
		)
		(fp_line
			(start 0.120396 0.3048)
			(end 0.120396 0.2794)
			(stroke
				(width 0.1)
				(type default)
			)
			(layer "F.Fab")
		)
		(fp_line
			(start 0.120396 0.2794)
			(end -0.12065 0.2794)
			(stroke
				(width 0.1)
				(type default)
			)
			(layer "F.Fab")
		)
		(fp_line
			(start -0.12065 0.3048)
			(end -0.67945 0.3048)
			(stroke
				(width 0.1)
				(type default)
			)
			(layer "F.Fab")
		)
		(fp_line
			(start -0.12065 0.2794)
			(end -0.12065 0.3048)
			(stroke
				(width 0.1)
				(type default)
			)
			(layer "F.Fab")
		)
		(fp_line
			(start -0.12065 -0.2794)
			(end 0.12065 -0.2794)
			(stroke
				(width 0.1)
				(type default)
			)
			(layer "F.Fab")
		)
		(fp_line
			(start -0.12065 -0.305054)
			(end -0.12065 -0.2794)
			(stroke
				(width 0.1)
				(type default)
			)
			(layer "F.Fab")
		)
		(fp_line
			(start -0.67945 0.3048)
			(end -0.67945 -0.305054)
			(stroke
				(width 0.1)
				(type default)
			)
			(layer "F.Fab")
		)
		(fp_line
			(start -0.67945 -0.305054)
			(end -0.12065 -0.305054)
			(stroke
				(width 0.1)
				(type default)
			)
			(layer "F.Fab")
		)
		(pad "1" smd circle
			(at -0.40005 0 180)
			(size 0 0)
			(layers "F.Cu" "F.Mask" "F.Paste")
			(net "SMB_M2_P0_1V8AUX_SCL_R")
		)
		(pad "2" smd circle
			(at 0.40005 0 180)
			(size 0 0)
			(layers "F.Cu" "F.Mask" "F.Paste")
			(net "SMB_M2_P0_1V8AUX_SCL")
		)
	)
	(footprint ""
		(layer "F.Cu")
		(at 421.92194 -109.271308 90)
		(property "Reference" "PC2162"
			(at 0 0 90)
			(layer "F.SilkS")
			(hide yes)
			(effects
				(font
					(size 1.27 1.27)
				)
			)
		)
		(property "Value" ""
			(at 0 0 90)
			(layer "F.Fab")
			(effects
				(font
					(size 1.27 1.27)
				)
			)
		)
		(duplicate_pad_numbers_are_jumpers no)
		(fp_line
			(start 0.7874 -0.4064)
			(end 0.7874 0.4064)
			(stroke
				(width 0.1524)
				(type default)
			)
			(layer "F.SilkS")
		)
		(fp_line
			(start -0.7874 -0.4064)
			(end 0.7874 -0.4064)
			(stroke
				(width 0.1524)
				(type default)
			)
			(layer "F.SilkS")
		)
		(fp_line
			(start 0.7874 0.4064)
			(end -0.7874 0.4064)
			(stroke
				(width 0.1524)
				(type default)
			)
			(layer "F.SilkS")
		)
		(fp_line
			(start -0.7874 0.4064)
			(end -0.7874 -0.4064)
			(stroke
				(width 0.1524)
				(type default)
			)
			(layer "F.SilkS")
		)
		(fp_line
			(start -0.12065 -0.305054)
			(end -0.12065 -0.2794)
			(stroke
				(width 0.1)
				(type default)
			)
			(layer "F.Fab")
		)
		(fp_line
			(start -0.67945 -0.305054)
			(end -0.12065 -0.305054)
			(stroke
				(width 0.1)
				(type default)
			)
			(layer "F.Fab")
		)
		(fp_line
			(start 0.67945 -0.3048)
			(end 0.67945 0.3048)
			(stroke
				(width 0.1)
				(type default)
			)
			(layer "F.Fab")
		)
		(fp_line
			(start 0.12065 -0.3048)
			(end 0.67945 -0.3048)
			(stroke
				(width 0.1)
				(type default)
			)
			(layer "F.Fab")
		)
		(fp_line
			(start 0.12065 -0.2794)
			(end 0.12065 -0.3048)
			(stroke
				(width 0.1)
				(type default)
			)
			(layer "F.Fab")
		)
		(fp_line
			(start -0.12065 -0.2794)
			(end 0.12065 -0.2794)
			(stroke
				(width 0.1)
				(type default)
			)
			(layer "F.Fab")
		)
		(fp_line
			(start 0.120396 0.2794)
			(end -0.12065 0.2794)
			(stroke
				(width 0.1)
				(type default)
			)
			(layer "F.Fab")
		)
		(fp_line
			(start -0.12065 0.2794)
			(end -0.12065 0.3048)
			(stroke
				(width 0.1)
				(type default)
			)
			(layer "F.Fab")
		)
		(fp_line
			(start 0.67945 0.3048)
			(end 0.120396 0.3048)
			(stroke
				(width 0.1)
				(type default)
			)
			(layer "F.Fab")
		)
		(fp_line
			(start 0.120396 0.3048)
			(end 0.120396 0.2794)
			(stroke
				(width 0.1)
				(type default)
			)
			(layer "F.Fab")
		)
		(fp_line
			(start -0.12065 0.3048)
			(end -0.67945 0.3048)
			(stroke
				(width 0.1)
				(type default)
			)
			(layer "F.Fab")
		)
		(fp_line
			(start -0.67945 0.3048)
			(end -0.67945 -0.305054)
			(stroke
				(width 0.1)
				(type default)
			)
			(layer "F.Fab")
		)
		(pad "1" smd circle
			(at -0.40005 0 90)
			(size 0 0)
			(layers "F.Cu" "F.Mask" "F.Paste")
			(net "P3V3_OCP_GATE_1")
		)
		(pad "2" smd circle
			(at 0.40005 0 90)
			(size 0 0)
			(layers "F.Cu" "F.Mask" "F.Paste")
			(net "GND")
		)
	)
)
